# S9S_MB_2U (Grand Teton) — schematic netlist excerpt (pin names and nets, part order shuffled) for the footprints in the layout excerpt that follows; sources: Cadence DE-HDL packaged netlist, KiCad conversion of 03242023_DA0F0TMBIJ0_F0T_Motherboard_J_brd_V01_OCP.brd

J22  SCONN288_ADR50017P087CC  SCONN288_ADR50017-P087CC IO  pkg DDR288S_1-1VXB  page 103
  VIN_BULK0  = P12V_S3_AUX_CPU1_NVDIMM
  RFU0  = TP_CHC_CPU1_DIMM2_FRU_0
  VIN_MGMT  = P3V3_AUX
  HSCL  = I3C_SPD_DDRABCD_CPU1_LVC1_SCL_5
  HSDA  = I3C_SPD_DDRABCD_CPU1_LVC1_SDA
  VSS0  = GND
  DQ0_A  = M_C_CPU1_SA_DQ<0>
  VSS1  = GND
  DQ1_A  = M_C_CPU1_SA_DQ<1>
  VSS2  = GND
  DQS0_A_T  = M_C_CPU1_SA_DQS_DP<0>
  DQS0_A_C  = M_C_CPU1_SA_DQS_DN<0>
  VSS3  = GND
  DQ4_A  = M_C_CPU1_SA_DQ<4>
  VSS4  = GND
  DQ5_A  = M_C_CPU1_SA_DQ<5>
  VSS5  = GND
  DQ8_A  = M_C_CPU1_SA_DQ<8>
  VSS6  = GND
  DQ9_A  = M_C_CPU1_SA_DQ<9>
  VSS7  = GND
  DQS1_A_T  = M_C_CPU1_SA_DQS_DP<1>
  DQS1_A_C  = M_C_CPU1_SA_DQS_DN<1>
  VSS8  = GND
  DQ12_A  = M_C_CPU1_SA_DQ<12>
  VSS9  = GND
  DQ13_A  = M_C_CPU1_SA_DQ<13>
  VSS10  = GND
  DQ16_A  = M_C_CPU1_SA_DQ<16>
  VSS11  = GND
  DQ17_A  = M_C_CPU1_SA_DQ<17>
  VSS12  = GND
  DQS2_A_T  = M_C_CPU1_SA_DQS_DP<2>
  DQS2_A_C  = M_C_CPU1_SA_DQS_DN<2>
  VSS13  = GND
  DQ20_A  = M_C_CPU1_SA_DQ<20>
  VSS14  = GND
  DQ21_A  = M_C_CPU1_SA_DQ<21>
  VSS15  = GND
  DQ24_A  = M_C_CPU1_SA_DQ<24>
  VSS16  = GND
  DQ25_A  = M_C_CPU1_SA_DQ<25>
  VSS17  = GND
  DQS3_A_T  = M_C_CPU1_SA_DQS_DP<3>
  DQS3_A_C  = M_C_CPU1_SA_DQS_DN<3>
  VSS18  = GND
  DQ28_A  = M_C_CPU1_SA_DQ<28>
  VSS19  = GND
  DQ29_A  = M_C_CPU1_SA_DQ<29>
  VSS20  = GND
  CB0_A  = M_C_CPU1_SA_CB<0>
  VSS21  = GND
  CB1_A  = M_C_CPU1_SA_CB<1>
  VSS22  = GND
  DQS4_A_T  = M_C_CPU1_SA_DQS_DP<4>
  DQS4_A_C  = M_C_CPU1_SA_DQS_DN<4>
  VSS23  = GND
  CB4_A  = M_C_CPU1_SA_CB<4>
  VSS24  = GND
  CB5_A  = M_C_CPU1_SA_CB<5>
  VSS25  = GND
  ALERT_N  = M_C_CPU1_ALERT_N
  VSS26  = GND
  CS0_A_N  = M_C_CPU1_SA_CS_N<2>
  VSS27  = GND
  CA0_A  = M_C_CPU1_SA_CA<0>
  VSS28  = GND
  CA2_A  = M_C_CPU1_SA_CA<2>
  VSS29  = GND
  CA4_A  = M_C_CPU1_SA_CA<4>
  VSS30  = GND
  CA6_A  = M_C_CPU1_SA_CA<6>
  VSS31  = GND
  PAR_A  = M_C_CPU1_SA_PAR
  VSS32  = GND
  CA0_B  = M_C_CPU1_SB_CA<0>
  VSS33  = GND
  CA2_B  = M_C_CPU1_SB_CA<2>
  VSS34  = GND
  CA4_B  = M_C_CPU1_SB_CA<4>
  VSS35  = GND
  CA6_B  = M_C_CPU1_SB_CA<6>
  VSS36  = GND
  CS0_B_N  = M_C_CPU1_SB_CS_N<2>
  VSS37  = GND
  \lbd||rsp_a_n\  = M_C_CPU1_SA_RSP<1>
  \lbs||rsp_b_n\  = M_C_CPU1_SB_RSP<1>
  VSS38  = GND
  CB4_B  = M_C_CPU1_SB_CB<4>
  VSS39  = GND
  CB5_B  = M_C_CPU1_SB_CB<5>
  VSS40  = GND
  \dqs9_b_t||tdqs9_b_t||dbi4_b_n\  = M_C_CPU1_SB_DQS_DP<9>
  \dqs9_b_c||tdqs9_b_c\  = M_C_CPU1_SB_DQS_DN<9>
  VSS41  = GND
  CB0_B  = M_C_CPU1_SB_CB<0>
  VSS42  = GND
  CB1_B  = M_C_CPU1_SB_CB<1>
  VSS43  = GND
  DQ0_B  = M_C_CPU1_SB_DQ<0>
  VSS44  = GND
  DQ1_B  = M_C_CPU1_SB_DQ<1>
  VSS45  = GND
  DQS0_B_T  = M_C_CPU1_SB_DQS_DP<0>
  DQS0_B_C  = M_C_CPU1_SB_DQS_DN<0>
  VSS46  = GND
  DQ4_B  = M_C_CPU1_SB_DQ<4>
  VSS47  = GND
  DQ5_B  = M_C_CPU1_SB_DQ<5>
  VSS48  = GND
  DQ8_B  = M_C_CPU1_SB_DQ<8>
  VSS49  = GND
  DQ9_B  = M_C_CPU1_SB_DQ<9>
  VSS50  = GND
  DQS1_B_T  = M_C_CPU1_SB_DQS_DP<1>
  DQS1_B_C  = M_C_CPU1_SB_DQS_DN<1>
  VSS51  = GND
  DQ12_B  = M_C_CPU1_SB_DQ<12>
  VSS52  = GND
  DQ13_B  = M_C_CPU1_SB_DQ<13>
  VSS53  = GND
  DQ16_B  = M_C_CPU1_SB_DQ<16>
  VSS54  = GND
  DQ17_B  = M_C_CPU1_SB_DQ<17>
  VSS55  = GND
  DQS2_B_T  = M_C_CPU1_SB_DQS_DP<2>
  DQS2_B_C  = M_C_CPU1_SB_DQS_DN<2>
  VSS56  = GND
  DQ20_B  = M_C_CPU1_SB_DQ<20>
  VSS57  = GND
  DQ21_B  = M_C_CPU1_SB_DQ<21>
  VSS58  = GND
  DQ24_B  = M_C_CPU1_SB_DQ<24>
  VSS59  = GND
  DQ25_B  = M_C_CPU1_SB_DQ<25>
  VSS60  = GND
  DQS3_B_T  = M_C_CPU1_SB_DQS_DP<3>
  DQS3_B_C  = M_C_CPU1_SB_DQS_DN<3>
  VSS61  = GND
  DQ28_B  = M_C_CPU1_SB_DQ<28>
  VSS62  = GND
  DQ29_B  = M_C_CPU1_SB_DQ<29>
  VSS63  = GND
  RFU1  = TP_CHC_CPU1_DIMM2_FRU_1
  VIN_BULK1  = P12V_S3_AUX_CPU1_NVDIMM
  VIN_BULK2  = P12V_S3_AUX_CPU1_NVDIMM
  \pwr_good||fail_n\  = PWRGD_CHC_CPU1_DIMM2
  HSA  = PD_CHC_CPU1_DIMM2_SAA
  RFU2  = TP_CHC_CPU1_DIMM2_FRU_2
  RFU3  = TP_CHC_CPU1_DIMM2_FRU_3
  VSS64  = GND
  DQ2_A  = M_C_CPU1_SA_DQ<2>
  VSS65  = GND
  DQ3_A  = M_C_CPU1_SA_DQ<3>
  VSS66  = GND
  \dqs5_a_c||tdqs5_a_c||dqs5_a_t||tdqs5_a_t\  = M_C_CPU1_SA_DQS_DN<5>
  \dqs5_a_t||tdqs5_a_t\  = M_C_CPU1_SA_DQS_DP<5>
  VSS67  = GND
  DQ6_A  = M_C_CPU1_SA_DQ<6>
  VSS68  = GND
  DQ7_A  = M_C_CPU1_SA_DQ<7>
  VSS69  = GND
  DQ10_A  = M_C_CPU1_SA_DQ<10>
  VSS70  = GND
  DQ11_A  = M_C_CPU1_SA_DQ<11>
  VSS71  = GND
  \dqs6_a_c||tdqs6_a_c||dqs6_a_t||tdqs6_a_t\  = M_C_CPU1_SA_DQS_DN<6>
  \dqs6_a_t||tdqs6_a_t\  = M_C_CPU1_SA_DQS_DP<6>
  VSS72  = GND
  DQ14_A  = M_C_CPU1_SA_DQ<14>
  VSS73  = GND
  DQ15_A  = M_C_CPU1_SA_DQ<15>
  VSS74  = GND
  DQ18_A  = M_C_CPU1_SA_DQ<18>
  VSS75  = GND
  DQ19_A  = M_C_CPU1_SA_DQ<19>
  VSS76  = GND
  \dqs7_a_c||tdqs7_a_c\  = M_C_CPU1_SA_DQS_DN<7>
  \dqs7_a_t||tdqs7_a_t\  = M_C_CPU1_SA_DQS_DP<7>
  VSS77  = GND
  DQ22_A  = M_C_CPU1_SA_DQ<22>
  VSS78  = GND
  DQ23_A  = M_C_CPU1_SA_DQ<23>
  VSS79  = GND
  DQ26_A  = M_C_CPU1_SA_DQ<26>
  VSS80  = GND
  DQ27_A  = M_C_CPU1_SA_DQ<27>
  VSS81  = GND
  \dqs8_a_c||tdqs8_a_c\  = M_C_CPU1_SA_DQS_DN<8>
  \dqs8_a_t||tdqs8_a_t\  = M_C_CPU1_SA_DQS_DP<8>
  VSS82  = GND
  DQ30_A  = M_C_CPU1_SA_DQ<30>
  VSS83  = GND
  DQ31_A  = M_C_CPU1_SA_DQ<31>
  VSS84  = GND
  CB2_A  = M_C_CPU1_SA_CB<2>
  VSS85  = GND
  CB3_A  = M_C_CPU1_SA_CB<3>
  VSS86  = GND
  \dqs9_a_c||tdqs9_a_c\  = M_C_CPU1_SA_DQS_DN<9>
  \dqs9_a_t||tdqs9_a_t\  = M_C_CPU1_SA_DQS_DP<9>
  VSS87  = GND
  CB6_A  = M_C_CPU1_SA_CB<6>
  VSS88  = GND
  CB7_A  = M_C_CPU1_SA_CB<7>
  VSS89  = GND
  RESET_N  = RST_M_CD_CPU1_FPGA_N
  VSS90  = GND
  CS1_A_N  = M_C_CPU1_SA_CS_N<3>
  VSS91  = GND
  CA1_A  = M_C_CPU1_SA_CA<1>
  VSS92  = GND
  CA3_A  = M_C_CPU1_SA_CA<3>
  VSS93  = GND
  CA5_A  = M_C_CPU1_SA_CA<5>
  VSS94  = GND
  CK_T  = M_C_CPU1_CLK_DP<1>
  CK_C  = M_C_CPU1_CLK_DN<1>
  VSS95  = GND
  RFU4  = TP_CHC_CPU1_DIMM2_FRU_4
  CA1_B  = M_C_CPU1_SB_CA<1>
  VSS96  = GND
  CA3_B  = M_C_CPU1_SB_CA<3>
  VSS97  = GND
  CA5_B  = M_C_CPU1_SB_CA<5>
  VSS98  = GND
  PAR_B  = M_C_CPU1_SB_PAR
  VSS99  = GND
  CS1_B_N  = M_C_CPU1_SB_CS_N<3>
  VSS100  = GND
  RFU5  = TP_CHC_CPU1_DIMM2_FRU_5
  RFU6  = TP_CHC_CPU1_DIMM2_FRU_6
  VSS101  = GND
  CB6_B  = M_C_CPU1_SB_CB<6>
  VSS102  = GND
  CB7_B  = M_C_CPU1_SB_CB<7>
  VSS103  = GND
  DQS4_B_C  = M_C_CPU1_SB_DQS_DN<4>
  DQS4_B_T  = M_C_CPU1_SB_DQS_DP<4>
  VSS104  = GND
  CB2_B  = M_C_CPU1_SB_CB<2>
  VSS105  = GND
  CB3_B  = M_C_CPU1_SB_CB<3>
  VSS106  = GND
  DQ2_B  = M_C_CPU1_SB_DQ<2>
  VSS107  = GND
  DQ3_B  = M_C_CPU1_SB_DQ<3>
  VSS108  = GND
  \dqs5_b_c||tdqs5_b_c\  = M_C_CPU1_SB_DQS_DN<5>
  \dqs5_b_t||tdqs5_b_t\  = M_C_CPU1_SB_DQS_DP<5>
  VSS109  = GND
  DQ6_B  = M_C_CPU1_SB_DQ<6>
  VSS110  = GND
  DQ7_B  = M_C_CPU1_SB_DQ<7>
  VSS111  = GND
  DQ10_B  = M_C_CPU1_SB_DQ<10>
  VSS112  = GND
  DQ11_B  = M_C_CPU1_SB_DQ<11>
  VSS113  = GND
  \dqs6_b_c||tdqs6_b_c\  = M_C_CPU1_SB_DQS_DN<6>
  \dqs6_b_t||tdqs6_b_t\  = M_C_CPU1_SB_DQS_DP<6>
  VSS114  = GND
  DQ14_B  = M_C_CPU1_SB_DQ<14>
  VSS115  = GND
  DQ15_B  = M_C_CPU1_SB_DQ<15>
  VSS116  = GND
  DQ18_B  = M_C_CPU1_SB_DQ<18>
  VSS117  = GND
  DQ19_B  = M_C_CPU1_SB_DQ<19>
  VSS118  = GND
  \dqs7_b_c||tdqs7_b_c\  = M_C_CPU1_SB_DQS_DN<7>
  \dqs7_b_t||tdqs7_b_t\  = M_C_CPU1_SB_DQS_DP<7>
  VSS119  = GND
  DQ22_B  = M_C_CPU1_SB_DQ<22>
  VSS120  = GND
  DQ23_B  = M_C_CPU1_SB_DQ<23>
  VSS121  = GND
  DQ26_B  = M_C_CPU1_SB_DQ<26>
  VSS122  = GND
  DQ27_B  = M_C_CPU1_SB_DQ<27>
  VSS123  = GND
  \dqs8_b_c||tdqs8_b_c\  = M_C_CPU1_SB_DQS_DN<8>
  \dqs8_b_t||tdqs8_b_t\  = M_C_CPU1_SB_DQS_DP<8>
  VSS124  = GND
  DQ30_B  = M_C_CPU1_SB_DQ<30>
  VSS125  = GND
  DQ31_B  = M_C_CPU1_SB_DQ<31>
  VSS126  = GND
  G1  = GND
  G2  = GND
  G3  = GND

(kicad_pcb
	(version 20260206)
	(generator "pcbnew")
	(generator_version "10.0")
	(general
		(thickness 1.6)
		(legacy_teardrops no)
	)
	(paper "A4")
	(title_block
		(title "03242023_DA0F0TMBIJ0_F0T_Motherboard_J_brd_V01_OCP.brd")
		(comment 1 "Grand Teton / footprint 501 of 6105 (J22), pads 183-228 of 291")
	)
	(layers
		(0 "F.Cu" signal "TOP")
		(4 "In1.Cu" signal "GND")
		(6 "In2.Cu" signal "IN1")
		(8 "In3.Cu" signal "GND1")
		(10 "In4.Cu" signal "IN2")
		(12 "In5.Cu" signal "GND2")
		(14 "In6.Cu" signal "IN3")
		(16 "In7.Cu" signal "GND3")
		(18 "In8.Cu" signal "VCC")
		(20 "In9.Cu" signal "VCC1")
		(22 "In10.Cu" signal "GND4")
		(24 "In11.Cu" signal "IN4")
		(26 "In12.Cu" signal "GND5")
		(28 "In13.Cu" signal "IN5")
		(30 "In14.Cu" signal "GND6")
		(32 "In15.Cu" signal "IN6")
		(34 "In16.Cu" signal "GND7")
		(2 "B.Cu" signal "BOTTOM")
		(9 "F.Adhes" user "F.Adhesive")
		(11 "B.Adhes" user "B.Adhesive")
		(13 "F.Paste" user "Package Geometry/Pastemask Top")
		(15 "B.Paste" user "Package Geometry/Pastemask Bottom")
		(5 "F.SilkS" user "Ref Des/Silkscreen Top")
		(7 "B.SilkS" user "Ref Des/Silkscreen Bottom")
		(1 "F.Mask" user "Board Geometry/Soldermask Top")
		(3 "B.Mask" user "Board Geometry/Soldermask Bottom")
		(17 "Dwgs.User" user "User.Drawings")
		(19 "Cmts.User" user "User.Comments")
		(21 "Eco1.User" user "User.Eco1")
		(23 "Eco2.User" user "User.Eco2")
		(25 "Edge.Cuts" user "Board Geometry/Outline")
		(27 "Margin" user)
		(31 "F.CrtYd" user "Package Geometry/Place Bound Top")
		(29 "B.CrtYd" user "Package Geometry/Place Bound Bottom")
		(35 "F.Fab" user "Ref Des/Assembly Top")
		(33 "B.Fab" user "Ref Des/Assembly Bottom")
	)
	(footprint ""
		(layer "F.Cu")
		(at 32.82188 -258.091686)
		(property "Reference" "J22"
			(at -1.420622 -81.912714 0)
			(unlocked yes)
			(layer "F.SilkS")
			(effects
				(font
					(size 0.7874 0.5842)
					(thickness 0.1524)
				)
				(justify left)
			)
		)
		(property "Value" ""
			(at 0 0 0)
			(layer "F.Fab")
			(effects
				(font
					(size 1.27 1.27)
				)
			)
		)
		(duplicate_pad_numbers_are_jumpers no)
		(pad "183" smd rect
			(at 2.050034 -31.025084 270)
			(size 0.519938 1.4986)
			(layers "F.Cu" "F.Mask" "F.Paste")
			(net "M_C_CPU1_SA_DQ<23>")
		)
		(pad "184" smd rect
			(at 2.050034 -30.174946 270)
			(size 0.519938 1.4986)
			(layers "F.Cu" "F.Mask" "F.Paste")
			(net "GND")
		)
		(pad "185" smd rect
			(at 2.050034 -29.325062 270)
			(size 0.519938 1.4986)
			(layers "F.Cu" "F.Mask" "F.Paste")
			(net "M_C_CPU1_SA_DQ<26>")
		)
		(pad "186" smd rect
			(at 2.050034 -28.474924 270)
			(size 0.519938 1.4986)
			(layers "F.Cu" "F.Mask" "F.Paste")
			(net "GND")
		)
		(pad "187" smd rect
			(at 2.050034 -27.62504 270)
			(size 0.519938 1.4986)
			(layers "F.Cu" "F.Mask" "F.Paste")
			(net "M_C_CPU1_SA_DQ<27>")
		)
		(pad "188" smd rect
			(at 2.050034 -26.774902 270)
			(size 0.519938 1.4986)
			(layers "F.Cu" "F.Mask" "F.Paste")
			(net "GND")
		)
		(pad "189" smd rect
			(at 2.050034 -25.925018 270)
			(size 0.519938 1.4986)
			(layers "F.Cu" "F.Mask" "F.Paste")
			(net "M_C_CPU1_SA_DQS_DN<8>")
		)
		(pad "190" smd rect
			(at 2.050034 -25.07488 270)
			(size 0.519938 1.4986)
			(layers "F.Cu" "F.Mask" "F.Paste")
			(net "M_C_CPU1_SA_DQS_DP<8>")
		)
		(pad "191" smd rect
			(at 2.050034 -24.224996 270)
			(size 0.519938 1.4986)
			(layers "F.Cu" "F.Mask" "F.Paste")
			(net "GND")
		)
		(pad "192" smd rect
			(at 2.050034 -23.375112 270)
			(size 0.519938 1.4986)
			(layers "F.Cu" "F.Mask" "F.Paste")
			(net "M_C_CPU1_SA_DQ<30>")
		)
		(pad "193" smd rect
			(at 2.050034 -22.524974 270)
			(size 0.519938 1.4986)
			(layers "F.Cu" "F.Mask" "F.Paste")
			(net "GND")
		)
		(pad "194" smd rect
			(at 2.050034 -21.67509 270)
			(size 0.519938 1.4986)
			(layers "F.Cu" "F.Mask" "F.Paste")
			(net "M_C_CPU1_SA_DQ<31>")
		)
		(pad "195" smd rect
			(at 2.050034 -20.824952 270)
			(size 0.519938 1.4986)
			(layers "F.Cu" "F.Mask" "F.Paste")
			(net "GND")
		)
		(pad "196" smd rect
			(at 2.050034 -19.975068 270)
			(size 0.519938 1.4986)
			(layers "F.Cu" "F.Mask" "F.Paste")
			(net "M_C_CPU1_SA_CB<2>")
		)
		(pad "197" smd rect
			(at 2.050034 -19.12493 270)
			(size 0.519938 1.4986)
			(layers "F.Cu" "F.Mask" "F.Paste")
			(net "GND")
		)
		(pad "198" smd rect
			(at 2.050034 -18.275046 270)
			(size 0.519938 1.4986)
			(layers "F.Cu" "F.Mask" "F.Paste")
			(net "M_C_CPU1_SA_CB<3>")
		)
		(pad "199" smd rect
			(at 2.050034 -17.424908 270)
			(size 0.519938 1.4986)
			(layers "F.Cu" "F.Mask" "F.Paste")
			(net "GND")
		)
		(pad "200" smd rect
			(at 2.050034 -16.575024 270)
			(size 0.519938 1.4986)
			(layers "F.Cu" "F.Mask" "F.Paste")
			(net "M_C_CPU1_SA_DQS_DN<9>")
		)
		(pad "201" smd rect
			(at 2.050034 -15.724886 270)
			(size 0.519938 1.4986)
			(layers "F.Cu" "F.Mask" "F.Paste")
			(net "M_C_CPU1_SA_DQS_DP<9>")
		)
		(pad "202" smd rect
			(at 2.050034 -14.875002 270)
			(size 0.519938 1.4986)
			(layers "F.Cu" "F.Mask" "F.Paste")
			(net "GND")
		)
		(pad "203" smd rect
			(at 2.050034 -14.025118 270)
			(size 0.519938 1.4986)
			(layers "F.Cu" "F.Mask" "F.Paste")
			(net "M_C_CPU1_SA_CB<6>")
		)
		(pad "204" smd rect
			(at 2.050034 -13.17498 270)
			(size 0.519938 1.4986)
			(layers "F.Cu" "F.Mask" "F.Paste")
			(net "GND")
		)
		(pad "205" smd rect
			(at 2.050034 -12.325096 270)
			(size 0.519938 1.4986)
			(layers "F.Cu" "F.Mask" "F.Paste")
			(net "M_C_CPU1_SA_CB<7>")
		)
		(pad "206" smd rect
			(at 2.050034 -11.474958 270)
			(size 0.519938 1.4986)
			(layers "F.Cu" "F.Mask" "F.Paste")
			(net "GND")
		)
		(pad "207" smd rect
			(at 2.050034 -10.625074 270)
			(size 0.519938 1.4986)
			(layers "F.Cu" "F.Mask" "F.Paste")
			(net "RST_M_CD_CPU1_FPGA_N")
		)
		(pad "208" smd rect
			(at 2.050034 -9.774936 270)
			(size 0.519938 1.4986)
			(layers "F.Cu" "F.Mask" "F.Paste")
			(net "GND")
		)
		(pad "209" smd rect
			(at 2.050034 -8.925052 270)
			(size 0.519938 1.4986)
			(layers "F.Cu" "F.Mask" "F.Paste")
			(net "M_C_CPU1_SA_CS_N<3>")
		)
		(pad "210" smd rect
			(at 2.050034 -8.074914 270)
			(size 0.519938 1.4986)
			(layers "F.Cu" "F.Mask" "F.Paste")
			(net "GND")
		)
		(pad "211" smd rect
			(at 2.050034 -7.22503 270)
			(size 0.519938 1.4986)
			(layers "F.Cu" "F.Mask" "F.Paste")
			(net "M_C_CPU1_SA_CA<1>")
		)
		(pad "212" smd rect
			(at 2.050034 -6.374892 270)
			(size 0.519938 1.4986)
			(layers "F.Cu" "F.Mask" "F.Paste")
			(net "GND")
		)
		(pad "213" smd rect
			(at 2.050034 -5.525008 270)
			(size 0.519938 1.4986)
			(layers "F.Cu" "F.Mask" "F.Paste")
			(net "M_C_CPU1_SA_CA<3>")
		)
		(pad "214" smd rect
			(at 2.050034 -4.675124 270)
			(size 0.519938 1.4986)
			(layers "F.Cu" "F.Mask" "F.Paste")
			(net "GND")
		)
		(pad "215" smd rect
			(at 2.050034 -3.824986 270)
			(size 0.519938 1.4986)
			(layers "F.Cu" "F.Mask" "F.Paste")
			(net "M_C_CPU1_SA_CA<5>")
		)
		(pad "216" smd rect
			(at 2.050034 -2.975102 270)
			(size 0.519938 1.4986)
			(layers "F.Cu" "F.Mask" "F.Paste")
			(net "GND")
		)
		(pad "217" smd rect
			(at 2.050034 -2.124964 270)
			(size 0.519938 1.4986)
			(layers "F.Cu" "F.Mask" "F.Paste")
			(net "M_C_CPU1_CLK_DP<1>")
		)
		(pad "218" smd rect
			(at 2.050034 -1.27508 270)
			(size 0.519938 1.4986)
			(layers "F.Cu" "F.Mask" "F.Paste")
			(net "M_C_CPU1_CLK_DN<1>")
		)
		(pad "219" smd rect
			(at 2.050034 -0.424942 270)
			(size 0.519938 1.4986)
			(layers "F.Cu" "F.Mask" "F.Paste")
			(net "GND")
		)
		(pad "220" smd rect
			(at 2.050034 5.525008 270)
			(size 0.519938 1.4986)
			(layers "F.Cu" "F.Mask" "F.Paste")
			(net "TP_CHC_CPU1_DIMM2_FRU_4")
		)
		(pad "221" smd rect
			(at 2.050034 6.374892 270)
			(size 0.519938 1.4986)
			(layers "F.Cu" "F.Mask" "F.Paste")
			(net "M_C_CPU1_SB_CA<1>")
		)
		(pad "222" smd rect
			(at 2.050034 7.22503 270)
			(size 0.519938 1.4986)
			(layers "F.Cu" "F.Mask" "F.Paste")
			(net "GND")
		)
		(pad "223" smd rect
			(at 2.050034 8.074914 270)
			(size 0.519938 1.4986)
			(layers "F.Cu" "F.Mask" "F.Paste")
			(net "M_C_CPU1_SB_CA<3>")
		)
		(pad "224" smd rect
			(at 2.050034 8.925052 270)
			(size 0.519938 1.4986)
			(layers "F.Cu" "F.Mask" "F.Paste")
			(net "GND")
		)
		(pad "225" smd rect
			(at 2.050034 9.774936 270)
			(size 0.519938 1.4986)
			(layers "F.Cu" "F.Mask" "F.Paste")
			(net "M_C_CPU1_SB_CA<5>")
		)
		(pad "226" smd rect
			(at 2.050034 10.625074 270)
			(size 0.519938 1.4986)
			(layers "F.Cu" "F.Mask" "F.Paste")
			(net "GND")
		)
		(pad "227" smd rect
			(at 2.050034 11.474958 270)
			(size 0.519938 1.4986)
			(layers "F.Cu" "F.Mask" "F.Paste")
			(net "M_C_CPU1_SB_PAR")
		)
		(pad "228" smd rect
			(at 2.050034 12.325096 270)
			(size 0.519938 1.4986)
			(layers "F.Cu" "F.Mask" "F.Paste")
			(net "GND")
		)
	)
)
